(kicad_pcb
	(version 20260206)
	(generator "pcbnew")
	(generator_version "10.0")
	(general
		(thickness 1.6)
		(legacy_teardrops no)
	)
	(paper "A4")
	(title_block
		(title "v2-pdb — ms_pdb_v2.brd")
		(comment 1 "Open CloudServer (Microsoft) / footprints 128-137 of 348")
	)
	(layers
		(0 "F.Cu" signal "TOP")
		(4 "In1.Cu" signal "GND")
		(6 "In2.Cu" signal "IN1")
		(8 "In3.Cu" signal "VCC")
		(10 "In4.Cu" signal "VCC1")
		(12 "In5.Cu" signal "IN2")
		(14 "In6.Cu" signal "GND1")
		(2 "B.Cu" signal "BOTTOM")
		(9 "F.Adhes" user "F.Adhesive")
		(11 "B.Adhes" user "B.Adhesive")
		(13 "F.Paste" user "Package Geometry/Pastemask Top")
		(15 "B.Paste" user "Package Geometry/Pastemask Bottom")
		(5 "F.SilkS" user "Ref Des/Silkscreen Top")
		(7 "B.SilkS" user "Ref Des/Silkscreen Bottom")
		(1 "F.Mask" user "Board Geometry/Soldermask Top")
		(3 "B.Mask" user "Board Geometry/Soldermask Bottom")
		(17 "Dwgs.User" user "User.Drawings")
		(19 "Cmts.User" user "User.Comments")
		(21 "Eco1.User" user "User.Eco1")
		(23 "Eco2.User" user "User.Eco2")
		(25 "Edge.Cuts" user "Board Geometry/Outline")
		(27 "Margin" user)
		(31 "F.CrtYd" user "Package Geometry/Place Bound Top")
		(29 "B.CrtYd" user "Package Geometry/Place Bound Bottom")
		(35 "F.Fab" user "Ref Des/Assembly Top")
		(33 "B.Fab" user "Ref Des/Assembly Bottom")
	)
	(footprint ""
		(layer "F.Cu")
		(at 13.429234 -326.145652 180)
		(property "Reference" "R145"
			(at -1.746758 -0.079502 0)
			(unlocked yes)
			(layer "F.SilkS")
			(effects
				(font
					(size 0.7874 0.5842)
					(thickness 0.1524)
				)
				(justify left)
			)
		)
		(property "Value" ""
			(at 0 0 180)
			(layer "F.Fab")
			(effects
				(font
					(size 1.27 1.27)
				)
			)
		)
		(duplicate_pad_numbers_are_jumpers no)
		(fp_line
			(start 0.7874 0.4064)
			(end -0.7874 0.4064)
			(stroke
				(width 0.1524)
				(type default)
			)
			(layer "F.SilkS")
		)
		(fp_line
			(start 0.7874 -0.4064)
			(end 0.7874 0.4064)
			(stroke
				(width 0.1524)
				(type default)
			)
			(layer "F.SilkS")
		)
		(fp_line
			(start -0.7874 0.4064)
			(end -0.7874 -0.4064)
			(stroke
				(width 0.1524)
				(type default)
			)
			(layer "F.SilkS")
		)
		(fp_line
			(start -0.7874 -0.4064)
			(end 0.7874 -0.4064)
			(stroke
				(width 0.1524)
				(type default)
			)
			(layer "F.SilkS")
		)
		(fp_poly
			(pts
				(xy -0.508 0.2794) (xy -0.508 0.2286) (xy -0.635 0.2286) (xy -0.635 -0.254) (xy -0.5334 -0.254)
				(xy -0.5334 -0.2794) (xy 0.5334 -0.2794) (xy 0.5334 -0.254) (xy 0.635 -0.254) (xy 0.635 0.254) (xy 0.5334 0.254)
				(xy 0.5334 0.2794)
			)
			(stroke
				(width 0)
				(type default)
			)
			(fill no)
			(layer "F.CrtYd")
		)
		(pad "1" smd rect
			(at 0.40005 0 180)
			(size 0.4572 0.508)
			(layers "F.Cu" "F.Mask" "F.Paste")
			(net "FAN4_TACH")
		)
		(pad "2" smd rect
			(at -0.40005 0 180)
			(size 0.4572 0.508)
			(layers "F.Cu" "F.Mask" "F.Paste")
			(net "P12V")
		)
	)
	(footprint ""
		(layer "F.Cu")
		(at 91.399868 -197.81012)
		(property "Reference" "H20"
			(at -5.1308 -5.23113 0)
			(unlocked yes)
			(layer "F.SilkS")
			(effects
				(font
					(size 0.7874 0.5842)
					(thickness 0.1524)
				)
				(justify left)
			)
		)
		(property "Value" ""
			(at 0 0 0)
			(layer "F.Fab")
			(effects
				(font
					(size 1.27 1.27)
				)
			)
		)
		(duplicate_pad_numbers_are_jumpers no)
		(fp_circle
			(center 0 0)
			(end 4.826 0)
			(stroke
				(width 0.1524)
				(type default)
			)
			(fill no)
			(layer "F.SilkS")
		)
		(fp_circle
			(center 0 0)
			(end 4.826 0)
			(stroke
				(width 0.1524)
				(type default)
			)
			(fill no)
			(layer "B.SilkS")
		)
		(fp_poly
			(pts
				(arc
					(start 0 4.0132)
					(mid 0 -4.0132)
					(end 0 4.0132)
				)
			)
			(stroke
				(width 0)
				(type default)
			)
			(fill no)
			(layer "F.CrtYd")
		)
		(pad "" np_thru_hole circle
			(at 0 0)
			(size 8.001 8.001)
			(drill 8.001)
			(layers "*.Cu" "*.Mask")
			(clearance 0.381)
			(thermal_gap 0.381)
		)
		(zone
			(layers "F.Cu" "B.Cu" "In1.Cu" "In2.Cu" "In3.Cu" "In4.Cu" "In5.Cu" "In6.Cu")
			(hatch none 0.5)
			(connect_pads
				(clearance 0)
			)
			(min_thickness 0.25)
			(keepout
				(tracks not_allowed)
				(vias allowed)
				(pads allowed)
				(copperpour not_allowed)
				(footprints allowed)
			)
			(placement
				(enabled no)
				(sheetname "")
			)
			(fill
				(thermal_gap 0.5)
				(thermal_bridge_width 0.5)
				(island_removal_mode 0)
			)
			(polygon
				(pts
					(arc
						(start 91.399868 -193.28892)
						(mid 91.399868 -202.33132)
						(end 91.399868 -193.28892)
					)
				)
			)
		)
	)
	(footprint ""
		(layer "F.Cu")
		(at 39.873936 -22.379432 180)
		(property "Reference" "R1"
			(at -2.42951 0.191262 0)
			(unlocked yes)
			(layer "F.SilkS")
			(effects
				(font
					(size 0.7874 0.5842)
					(thickness 0.1524)
				)
				(justify left)
			)
		)
		(property "Value" ""
			(at 0 0 180)
			(layer "F.Fab")
			(effects
				(font
					(size 1.27 1.27)
				)
			)
		)
		(duplicate_pad_numbers_are_jumpers no)
		(fp_line
			(start 0.7874 0.4064)
			(end -0.7874 0.4064)
			(stroke
				(width 0.1524)
				(type default)
			)
			(layer "F.SilkS")
		)
		(fp_line
			(start 0.7874 -0.4064)
			(end 0.7874 0.4064)
			(stroke
				(width 0.1524)
				(type default)
			)
			(layer "F.SilkS")
		)
		(fp_line
			(start -0.7874 0.4064)
			(end -0.7874 -0.4064)
			(stroke
				(width 0.1524)
				(type default)
			)
			(layer "F.SilkS")
		)
		(fp_line
			(start -0.7874 -0.4064)
			(end 0.7874 -0.4064)
			(stroke
				(width 0.1524)
				(type default)
			)
			(layer "F.SilkS")
		)
		(fp_poly
			(pts
				(xy -0.508 0.2794) (xy -0.508 0.2286) (xy -0.635 0.2286) (xy -0.635 -0.254) (xy -0.5334 -0.254)
				(xy -0.5334 -0.2794) (xy 0.5334 -0.2794) (xy 0.5334 -0.254) (xy 0.635 -0.254) (xy 0.635 0.254) (xy 0.5334 0.254)
				(xy 0.5334 0.2794)
			)
			(stroke
				(width 0)
				(type default)
			)
			(fill no)
			(layer "F.CrtYd")
		)
		(pad "1" smd rect
			(at 0.40005 0 180)
			(size 0.4572 0.508)
			(layers "F.Cu" "F.Mask" "F.Paste")
			(net "PSU1_REMOTE_P")
		)
		(pad "2" smd rect
			(at -0.40005 0 180)
			(size 0.4572 0.508)
			(layers "F.Cu" "F.Mask" "F.Paste")
			(net "P12V")
		)
	)
	(footprint ""
		(layer "F.Cu")
		(at 68.972938 -64.481456 -90)
		(property "Reference" "C8"
			(at -2.737104 0.062992 90)
			(unlocked yes)
			(layer "F.SilkS")
			(effects
				(font
					(size 0.7874 0.5842)
					(thickness 0.1524)
				)
			)
		)
		(property "Value" ""
			(at 0 0 270)
			(layer "F.Fab")
			(effects
				(font
					(size 1.27 1.27)
				)
			)
		)
		(duplicate_pad_numbers_are_jumpers no)
		(fp_line
			(start -1.2954 0.5842)
			(end -1.2954 -0.5842)
			(stroke
				(width 0.1524)
				(type default)
			)
			(layer "F.SilkS")
		)
		(fp_line
			(start 1.2954 0.5842)
			(end -1.2954 0.5842)
			(stroke
				(width 0.1524)
				(type default)
			)
			(layer "F.SilkS")
		)
		(fp_line
			(start -1.2954 -0.5842)
			(end 1.2954 -0.5842)
			(stroke
				(width 0.1524)
				(type default)
			)
			(layer "F.SilkS")
		)
		(fp_line
			(start 0 -0.5842)
			(end 0 0.5842)
			(stroke
				(width 0.1524)
				(type default)
			)
			(layer "F.SilkS")
		)
		(fp_line
			(start 1.2954 -0.5842)
			(end 1.2954 0.5842)
			(stroke
				(width 0.1524)
				(type default)
			)
			(layer "F.SilkS")
		)
		(fp_poly
			(pts
				(xy 0.8636 -0.4572) (xy 0.8636 -0.3556) (xy 1.143 -0.3556) (xy 1.143 0.3556) (xy 0.8636 0.3556)
				(xy 0.8636 0.4572) (xy -0.8636 0.4572) (xy -0.8636 0.3556) (xy -1.143 0.3556) (xy -1.143 -0.3556)
				(xy -0.8636 -0.3556) (xy -0.8636 -0.4572)
			)
			(stroke
				(width 0)
				(type default)
			)
			(fill no)
			(layer "F.CrtYd")
		)
		(fp_line
			(start -0.884936 0.504952)
			(end -0.884936 -0.504952)
			(stroke
				(width 0.1)
				(type default)
			)
			(layer "F.Fab")
		)
		(fp_line
			(start 0.884936 0.504952)
			(end -0.884936 0.504952)
			(stroke
				(width 0.1)
				(type default)
			)
			(layer "F.Fab")
		)
		(fp_line
			(start -0.884936 -0.504952)
			(end 0.884936 -0.504952)
			(stroke
				(width 0.1)
				(type default)
			)
			(layer "F.Fab")
		)
		(fp_line
			(start 0.884936 -0.504952)
			(end 0.884936 0.504952)
			(stroke
				(width 0.1)
				(type default)
			)
			(layer "F.Fab")
		)
		(pad "1" smd rect
			(at 0.7366 0)
			(size 0.7112 0.8128)
			(layers "F.Cu" "F.Mask" "F.Paste")
			(net "P12V")
		)
		(pad "2" smd rect
			(at -0.7366 0)
			(size 0.7112 0.8128)
			(layers "F.Cu" "F.Mask" "F.Paste")
			(net "GND")
		)
	)
	(footprint ""
		(layer "F.Cu")
		(at 68.716144 -117.627146 180)
		(property "Reference" "R116"
			(at 1.552448 -1.398016 0)
			(unlocked yes)
			(layer "F.SilkS")
			(effects
				(font
					(size 0.7874 0.5842)
					(thickness 0.1524)
				)
				(justify left)
			)
		)
		(property "Value" ""
			(at 0 0 180)
			(layer "F.Fab")
			(effects
				(font
					(size 1.27 1.27)
				)
			)
		)
		(duplicate_pad_numbers_are_jumpers no)
		(fp_line
			(start 0.7874 0.4064)
			(end -0.7874 0.4064)
			(stroke
				(width 0.1524)
				(type default)
			)
			(layer "F.SilkS")
		)
		(fp_line
			(start 0.7874 -0.4064)
			(end 0.7874 0.4064)
			(stroke
				(width 0.1524)
				(type default)
			)
			(layer "F.SilkS")
		)
		(fp_line
			(start -0.7874 0.4064)
			(end -0.7874 -0.4064)
			(stroke
				(width 0.1524)
				(type default)
			)
			(layer "F.SilkS")
		)
		(fp_line
			(start -0.7874 -0.4064)
			(end 0.7874 -0.4064)
			(stroke
				(width 0.1524)
				(type default)
			)
			(layer "F.SilkS")
		)
		(fp_poly
			(pts
				(xy -0.508 0.2794) (xy -0.508 0.2286) (xy -0.635 0.2286) (xy -0.635 -0.254) (xy -0.5334 -0.254)
				(xy -0.5334 -0.2794) (xy 0.5334 -0.2794) (xy 0.5334 -0.254) (xy 0.635 -0.254) (xy 0.635 0.254) (xy 0.5334 0.254)
				(xy 0.5334 0.2794)
			)
			(stroke
				(width 0)
				(type default)
			)
			(fill no)
			(layer "F.CrtYd")
		)
		(pad "1" smd rect
			(at 0.40005 0 180)
			(size 0.4572 0.508)
			(layers "F.Cu" "F.Mask" "F.Paste")
			(net "PSU2_REMOTE_R2_N")
		)
		(pad "2" smd rect
			(at -0.40005 0 180)
			(size 0.4572 0.508)
			(layers "F.Cu" "F.Mask" "F.Paste")
			(net "GND")
		)
	)
	(footprint ""
		(layer "F.Cu")
		(at 70.997572 -350.498664 90)
		(property "Reference" "C61"
			(at 1.158748 0.151892 90)
			(unlocked yes)
			(layer "F.SilkS")
			(effects
				(font
					(size 0.7874 0.5842)
					(thickness 0.1524)
				)
				(justify left)
			)
		)
		(property "Value" ""
			(at 0 0 90)
			(layer "F.Fab")
			(effects
				(font
					(size 1.27 1.27)
				)
			)
		)
		(duplicate_pad_numbers_are_jumpers no)
		(fp_line
			(start 0.7874 -0.4064)
			(end 0.7874 0.4064)
			(stroke
				(width 0.1524)
				(type default)
			)
			(layer "F.SilkS")
		)
		(fp_line
			(start -0.7874 -0.4064)
			(end 0.7874 -0.4064)
			(stroke
				(width 0.1524)
				(type default)
			)
			(layer "F.SilkS")
		)
		(fp_line
			(start 0 0.381)
			(end 0 -0.381)
			(stroke
				(width 0.1524)
				(type default)
			)
			(layer "F.SilkS")
		)
		(fp_line
			(start 0.7874 0.4064)
			(end -0.7874 0.4064)
			(stroke
				(width 0.1524)
				(type default)
			)
			(layer "F.SilkS")
		)
		(fp_line
			(start -0.7874 0.4064)
			(end -0.7874 -0.4064)
			(stroke
				(width 0.1524)
				(type default)
			)
			(layer "F.SilkS")
		)
		(fp_poly
			(pts
				(xy -0.5334 0.254) (xy -0.635 0.254) (xy -0.635 0.2286) (xy -0.635 -0.254) (xy -0.5334 -0.254) (xy -0.5334 -0.2794)
				(xy 0.5334 -0.2794) (xy 0.5334 -0.254) (xy 0.635 -0.254) (xy 0.635 0.254) (xy 0.5334 0.254) (xy 0.5334 0.2794)
				(xy -0.508 0.2794) (xy -0.5334 0.2794)
			)
			(stroke
				(width 0)
				(type default)
			)
			(fill no)
			(layer "F.CrtYd")
		)
		(pad "1" smd rect
			(at 0.40005 0 90)
			(size 0.4572 0.508)
			(layers "F.Cu" "F.Mask" "F.Paste")
			(net "P12V")
		)
		(pad "2" smd rect
			(at -0.40005 0 90)
			(size 0.4572 0.508)
			(layers "F.Cu" "F.Mask" "F.Paste")
			(net "GND")
		)
	)
	(footprint ""
		(layer "F.Cu")
		(at 50.100738 -62.882272 180)
		(property "Reference" "CE3"
			(at -4.025646 2.458974 0)
			(unlocked yes)
			(layer "F.SilkS")
			(effects
				(font
					(size 0.7874 0.5842)
					(thickness 0.1524)
				)
				(justify left)
			)
		)
		(property "Value" ""
			(at 0 0 180)
			(layer "F.Fab")
			(effects
				(font
					(size 1.27 1.27)
				)
			)
		)
		(duplicate_pad_numbers_are_jumpers no)
		(fp_line
			(start 0 -4.2672)
			(end 0 4.2672)
			(stroke
				(width 0.1524)
				(type default)
			)
			(layer "F.SilkS")
		)
		(fp_circle
			(center 0 0)
			(end -4.2672 0)
			(stroke
				(width 0.1524)
				(type default)
			)
			(fill no)
			(layer "F.SilkS")
		)
		(fp_poly
			(pts
				(arc
					(start 0 -4.2672)
					(mid 4.2672 0)
					(end 0 4.2672)
				)
			)
			(stroke
				(width 0)
				(type default)
			)
			(fill yes)
			(layer "F.SilkS")
		)
		(fp_poly
			(pts
				(xy -2.5146 -0.762) (xy -0.9906 -0.762) (xy -0.9906 0.762) (xy -2.5146 0.762)
			)
			(stroke
				(width 0)
				(type default)
			)
			(fill no)
			(layer "B.CrtYd")
		)
		(fp_poly
			(pts
				(arc
					(start 1.7526 0.762)
					(mid 2.291415 -0.538815)
					(end 0.9906 0)
				)
				(arc
					(start 0.9906 0.0254)
					(mid 1.206345 0.546255)
					(end 1.7272 0.762)
				)
			)
			(stroke
				(width 0)
				(type default)
			)
			(fill no)
			(layer "B.CrtYd")
		)
		(fp_poly
			(pts
				(arc
					(start -4.2672 0)
					(mid 4.2672 0)
					(end -4.2672 0)
				)
			)
			(stroke
				(width 0)
				(type default)
			)
			(fill no)
			(layer "F.CrtYd")
		)
		(fp_circle
			(center 0 0)
			(end -4.2672 0)
			(stroke
				(width 0.1)
				(type default)
			)
			(fill no)
			(layer "F.Fab")
		)
		(fp_text user "+"
			(at -5.750306 -0.61595 180)
			(unlocked yes)
			(layer "F.SilkS")
			(effects
				(font
					(size 1.905 1.4224)
					(thickness 0.1524)
				)
				(justify left)
			)
		)
		(fp_text user "+"
			(at -5.6642 -0.34925 180)
			(unlocked yes)
			(layer "F.Fab")
			(effects
				(font
					(size 1.905 1.4224)
					(thickness 0.000001)
				)
				(justify left)
			)
		)
		(pad "1" thru_hole rect
			(at -1.75006 0 180)
			(size 1.397 1.397)
			(drill 0.9144)
			(layers "*.Cu" "*.Mask")
			(remove_unused_layers no)
			(net "P12V")
			(clearance 0.0127)
			(thermal_gap 0.0127)
			(padstack
				(mode front_inner_back)
				(layer "Inner"
					(shape circle)
					(size 1.397 1.397)
					(clearance 0.0127)
				)
				(layer "B.Cu"
					(shape rect)
					(size 1.397 1.397)
					(clearance 0.0127)
				)
			)
		)
		(pad "2" thru_hole circle
			(at 1.75006 0 180)
			(size 1.397 1.397)
			(drill 0.9144)
			(layers "*.Cu" "*.Mask")
			(remove_unused_layers no)
			(net "GND")
			(clearance 0.0127)
			(thermal_gap 0.0127)
		)
	)
	(footprint ""
		(layer "F.Cu")
		(at 81.29143 -508.115824 -90)
		(property "Reference" "C79"
			(at 3.578606 0.032512 90)
			(unlocked yes)
			(layer "F.SilkS")
			(effects
				(font
					(size 0.7874 0.5842)
					(thickness 0.1524)
				)
				(justify left)
			)
		)
		(property "Value" ""
			(at 0 0 270)
			(layer "F.Fab")
			(effects
				(font
					(size 1.27 1.27)
				)
			)
		)
		(duplicate_pad_numbers_are_jumpers no)
		(fp_line
			(start -0.7874 0.4064)
			(end -0.7874 -0.4064)
			(stroke
				(width 0.1524)
				(type default)
			)
			(layer "F.SilkS")
		)
		(fp_line
			(start 0.7874 0.4064)
			(end -0.7874 0.4064)
			(stroke
				(width 0.1524)
				(type default)
			)
			(layer "F.SilkS")
		)
		(fp_line
			(start 0 0.381)
			(end 0 -0.381)
			(stroke
				(width 0.1524)
				(type default)
			)
			(layer "F.SilkS")
		)
		(fp_line
			(start -0.7874 -0.4064)
			(end 0.7874 -0.4064)
			(stroke
				(width 0.1524)
				(type default)
			)
			(layer "F.SilkS")
		)
		(fp_line
			(start 0.7874 -0.4064)
			(end 0.7874 0.4064)
			(stroke
				(width 0.1524)
				(type default)
			)
			(layer "F.SilkS")
		)
		(fp_poly
			(pts
				(xy -0.5334 0.254) (xy -0.635 0.254) (xy -0.635 0.2286) (xy -0.635 -0.254) (xy -0.5334 -0.254) (xy -0.5334 -0.2794)
				(xy 0.5334 -0.2794) (xy 0.5334 -0.254) (xy 0.635 -0.254) (xy 0.635 0.254) (xy 0.5334 0.254) (xy 0.5334 0.2794)
				(xy -0.508 0.2794) (xy -0.5334 0.2794)
			)
			(stroke
				(width 0)
				(type default)
			)
			(fill no)
			(layer "F.CrtYd")
		)
		(pad "1" smd rect
			(at 0.40005 0 270)
			(size 0.4572 0.508)
			(layers "F.Cu" "F.Mask" "F.Paste")
			(net "P12V")
		)
		(pad "2" smd rect
			(at -0.40005 0 270)
			(size 0.4572 0.508)
			(layers "F.Cu" "F.Mask" "F.Paste")
			(net "GND")
		)
	)
	(footprint ""
		(layer "F.Cu")
		(at 67.101974 -216.615772 90)
		(property "Reference" "C42"
			(at 1.20523 -0.200406 90)
			(unlocked yes)
			(layer "F.SilkS")
			(effects
				(font
					(size 0.7874 0.5842)
					(thickness 0.1524)
				)
				(justify left)
			)
		)
		(property "Value" ""
			(at 0 0 90)
			(layer "F.Fab")
			(effects
				(font
					(size 1.27 1.27)
				)
			)
		)
		(duplicate_pad_numbers_are_jumpers no)
		(fp_line
			(start 0.7874 -0.4064)
			(end 0.7874 0.4064)
			(stroke
				(width 0.1524)
				(type default)
			)
			(layer "F.SilkS")
		)
		(fp_line
			(start -0.7874 -0.4064)
			(end 0.7874 -0.4064)
			(stroke
				(width 0.1524)
				(type default)
			)
			(layer "F.SilkS")
		)
		(fp_line
			(start 0 0.381)
			(end 0 -0.381)
			(stroke
				(width 0.1524)
				(type default)
			)
			(layer "F.SilkS")
		)
		(fp_line
			(start 0.7874 0.4064)
			(end -0.7874 0.4064)
			(stroke
				(width 0.1524)
				(type default)
			)
			(layer "F.SilkS")
		)
		(fp_line
			(start -0.7874 0.4064)
			(end -0.7874 -0.4064)
			(stroke
				(width 0.1524)
				(type default)
			)
			(layer "F.SilkS")
		)
		(fp_poly
			(pts
				(xy -0.5334 0.254) (xy -0.635 0.254) (xy -0.635 0.2286) (xy -0.635 -0.254) (xy -0.5334 -0.254) (xy -0.5334 -0.2794)
				(xy 0.5334 -0.2794) (xy 0.5334 -0.254) (xy 0.635 -0.254) (xy 0.635 0.254) (xy 0.5334 0.254) (xy 0.5334 0.2794)
				(xy -0.508 0.2794) (xy -0.5334 0.2794)
			)
			(stroke
				(width 0)
				(type default)
			)
			(fill no)
			(layer "F.CrtYd")
		)
		(pad "1" smd rect
			(at 0.40005 0 90)
			(size 0.4572 0.508)
			(layers "F.Cu" "F.Mask" "F.Paste")
			(net "P12V")
		)
		(pad "2" smd rect
			(at -0.40005 0 90)
			(size 0.4572 0.508)
			(layers "F.Cu" "F.Mask" "F.Paste")
			(net "GND")
		)
	)
	(footprint ""
		(layer "F.Cu")
		(at 79.524606 -18.749772 -90)
		(property "Reference" "C5"
			(at -1.75133 0.0254 90)
			(unlocked yes)
			(layer "F.SilkS")
			(effects
				(font
					(size 0.7874 0.5842)
					(thickness 0.1524)
				)
				(justify left)
			)
		)
		(property "Value" ""
			(at 0 0 270)
			(layer "F.Fab")
			(effects
				(font
					(size 1.27 1.27)
				)
			)
		)
		(duplicate_pad_numbers_are_jumpers no)
		(fp_line
			(start -0.7874 0.4064)
			(end -0.7874 -0.4064)
			(stroke
				(width 0.1524)
				(type default)
			)
			(layer "F.SilkS")
		)
		(fp_line
			(start 0.7874 0.4064)
			(end -0.7874 0.4064)
			(stroke
				(width 0.1524)
				(type default)
			)
			(layer "F.SilkS")
		)
		(fp_line
			(start 0 0.381)
			(end 0 -0.381)
			(stroke
				(width 0.1524)
				(type default)
			)
			(layer "F.SilkS")
		)
		(fp_line
			(start -0.7874 -0.4064)
			(end 0.7874 -0.4064)
			(stroke
				(width 0.1524)
				(type default)
			)
			(layer "F.SilkS")
		)
		(fp_line
			(start 0.7874 -0.4064)
			(end 0.7874 0.4064)
			(stroke
				(width 0.1524)
				(type default)
			)
			(layer "F.SilkS")
		)
		(fp_poly
			(pts
				(xy -0.5334 0.254) (xy -0.635 0.254) (xy -0.635 0.2286) (xy -0.635 -0.254) (xy -0.5334 -0.254) (xy -0.5334 -0.2794)
				(xy 0.5334 -0.2794) (xy 0.5334 -0.254) (xy 0.635 -0.254) (xy 0.635 0.254) (xy 0.5334 0.254) (xy 0.5334 0.2794)
				(xy -0.508 0.2794) (xy -0.5334 0.2794)
			)
			(stroke
				(width 0)
				(type default)
			)
			(fill no)
			(layer "F.CrtYd")
		)
		(pad "1" smd rect
			(at 0.40005 0 270)
			(size 0.4572 0.508)
			(layers "F.Cu" "F.Mask" "F.Paste")
			(net "P12V")
		)
		(pad "2" smd rect
			(at -0.40005 0 270)
			(size 0.4572 0.508)
			(layers "F.Cu" "F.Mask" "F.Paste")
			(net "GND")
		)
	)
)
